(kicad_pcb
	(version 20260206)
	(generator "pcbnew")
	(generator_version "10.0")
	(general
		(thickness 1.6)
		(legacy_teardrops no)
	)
	(paper "A4")
	(title_block
		(title "03242023_DA0F0TMBIJ0_F0T_Motherboard_J_brd_V01_OCP.brd")
		(comment 1 "Grand Teton / footprints 224-229 of 6105")
	)
	(layers
		(0 "F.Cu" signal "TOP")
		(4 "In1.Cu" signal "GND")
		(6 "In2.Cu" signal "IN1")
		(8 "In3.Cu" signal "GND1")
		(10 "In4.Cu" signal "IN2")
		(12 "In5.Cu" signal "GND2")
		(14 "In6.Cu" signal "IN3")
		(16 "In7.Cu" signal "GND3")
		(18 "In8.Cu" signal "VCC")
		(20 "In9.Cu" signal "VCC1")
		(22 "In10.Cu" signal "GND4")
		(24 "In11.Cu" signal "IN4")
		(26 "In12.Cu" signal "GND5")
		(28 "In13.Cu" signal "IN5")
		(30 "In14.Cu" signal "GND6")
		(32 "In15.Cu" signal "IN6")
		(34 "In16.Cu" signal "GND7")
		(2 "B.Cu" signal "BOTTOM")
		(9 "F.Adhes" user "F.Adhesive")
		(11 "B.Adhes" user "B.Adhesive")
		(13 "F.Paste" user "Package Geometry/Pastemask Top")
		(15 "B.Paste" user "Package Geometry/Pastemask Bottom")
		(5 "F.SilkS" user "Ref Des/Silkscreen Top")
		(7 "B.SilkS" user "Ref Des/Silkscreen Bottom")
		(1 "F.Mask" user "Board Geometry/Soldermask Top")
		(3 "B.Mask" user "Board Geometry/Soldermask Bottom")
		(17 "Dwgs.User" user "User.Drawings")
		(19 "Cmts.User" user "User.Comments")
		(21 "Eco1.User" user "User.Eco1")
		(23 "Eco2.User" user "User.Eco2")
		(25 "Edge.Cuts" user "Board Geometry/Outline")
		(27 "Margin" user)
		(31 "F.CrtYd" user "Package Geometry/Place Bound Top")
		(29 "B.CrtYd" user "Package Geometry/Place Bound Bottom")
		(35 "F.Fab" user "Ref Des/Assembly Top")
		(33 "B.Fab" user "Ref Des/Assembly Bottom")
	)
	(footprint ""
		(layer "F.Cu")
		(at 283.826712 -362.984796)
		(property "Reference" "PR633"
			(at 0 0 0)
			(layer "F.SilkS")
			(hide yes)
			(effects
				(font
					(size 1.27 1.27)
				)
			)
		)
		(property "Value" ""
			(at 0 0 0)
			(layer "F.Fab")
			(effects
				(font
					(size 1.27 1.27)
				)
			)
		)
		(duplicate_pad_numbers_are_jumpers no)
		(fp_line
			(start -0.7874 -0.4064)
			(end 0.7874 -0.4064)
			(stroke
				(width 0.1524)
				(type default)
			)
			(layer "F.SilkS")
		)
		(fp_line
			(start -0.7874 0.4064)
			(end -0.7874 -0.4064)
			(stroke
				(width 0.1524)
				(type default)
			)
			(layer "F.SilkS")
		)
		(fp_line
			(start 0.7874 -0.4064)
			(end 0.7874 0.4064)
			(stroke
				(width 0.1524)
				(type default)
			)
			(layer "F.SilkS")
		)
		(fp_line
			(start 0.7874 0.4064)
			(end -0.7874 0.4064)
			(stroke
				(width 0.1524)
				(type default)
			)
			(layer "F.SilkS")
		)
		(fp_line
			(start -0.67945 -0.305054)
			(end -0.12065 -0.305054)
			(stroke
				(width 0.1)
				(type default)
			)
			(layer "F.Fab")
		)
		(fp_line
			(start -0.67945 0.3048)
			(end -0.67945 -0.305054)
			(stroke
				(width 0.1)
				(type default)
			)
			(layer "F.Fab")
		)
		(fp_line
			(start -0.12065 -0.305054)
			(end -0.12065 -0.2794)
			(stroke
				(width 0.1)
				(type default)
			)
			(layer "F.Fab")
		)
		(fp_line
			(start -0.12065 -0.2794)
			(end 0.12065 -0.2794)
			(stroke
				(width 0.1)
				(type default)
			)
			(layer "F.Fab")
		)
		(fp_line
			(start -0.12065 0.2794)
			(end -0.12065 0.3048)
			(stroke
				(width 0.1)
				(type default)
			)
			(layer "F.Fab")
		)
		(fp_line
			(start -0.12065 0.3048)
			(end -0.67945 0.3048)
			(stroke
				(width 0.1)
				(type default)
			)
			(layer "F.Fab")
		)
		(fp_line
			(start 0.120396 0.2794)
			(end -0.12065 0.2794)
			(stroke
				(width 0.1)
				(type default)
			)
			(layer "F.Fab")
		)
		(fp_line
			(start 0.120396 0.3048)
			(end 0.120396 0.2794)
			(stroke
				(width 0.1)
				(type default)
			)
			(layer "F.Fab")
		)
		(fp_line
			(start 0.12065 -0.3048)
			(end 0.67945 -0.3048)
			(stroke
				(width 0.1)
				(type default)
			)
			(layer "F.Fab")
		)
		(fp_line
			(start 0.12065 -0.2794)
			(end 0.12065 -0.3048)
			(stroke
				(width 0.1)
				(type default)
			)
			(layer "F.Fab")
		)
		(fp_line
			(start 0.67945 -0.3048)
			(end 0.67945 0.3048)
			(stroke
				(width 0.1)
				(type default)
			)
			(layer "F.Fab")
		)
		(fp_line
			(start 0.67945 0.3048)
			(end 0.120396 0.3048)
			(stroke
				(width 0.1)
				(type default)
			)
			(layer "F.Fab")
		)
		(pad "1" smd circle
			(at -0.40005 0)
			(size 0 0)
			(layers "F.Cu" "F.Mask" "F.Paste")
			(net "P3V3")
		)
		(pad "2" smd circle
			(at 0.40005 0)
			(size 0 0)
			(layers "F.Cu" "F.Mask" "F.Paste")
			(net "PVCCFA_EHV_FIVRA_CPU0_PVCC2")
		)
	)
	(footprint ""
		(layer "F.Cu")
		(at 454.758552 -382.660652 180)
		(property "Reference" "PC1847"
			(at 0 0 180)
			(layer "F.SilkS")
			(hide yes)
			(effects
				(font
					(size 1.27 1.27)
				)
			)
		)
		(property "Value" ""
			(at 0 0 180)
			(layer "F.Fab")
			(effects
				(font
					(size 1.27 1.27)
				)
			)
		)
		(duplicate_pad_numbers_are_jumpers no)
		(fp_line
			(start 0.7874 0.4064)
			(end -0.7874 0.4064)
			(stroke
				(width 0.1524)
				(type default)
			)
			(layer "F.SilkS")
		)
		(fp_line
			(start 0.7874 -0.4064)
			(end 0.7874 0.4064)
			(stroke
				(width 0.1524)
				(type default)
			)
			(layer "F.SilkS")
		)
		(fp_line
			(start -0.7874 0.4064)
			(end -0.7874 -0.4064)
			(stroke
				(width 0.1524)
				(type default)
			)
			(layer "F.SilkS")
		)
		(fp_line
			(start -0.7874 -0.4064)
			(end 0.7874 -0.4064)
			(stroke
				(width 0.1524)
				(type default)
			)
			(layer "F.SilkS")
		)
		(fp_line
			(start 0.67945 0.3048)
			(end 0.120396 0.3048)
			(stroke
				(width 0.1)
				(type default)
			)
			(layer "F.Fab")
		)
		(fp_line
			(start 0.67945 -0.3048)
			(end 0.67945 0.3048)
			(stroke
				(width 0.1)
				(type default)
			)
			(layer "F.Fab")
		)
		(fp_line
			(start 0.12065 -0.2794)
			(end 0.12065 -0.3048)
			(stroke
				(width 0.1)
				(type default)
			)
			(layer "F.Fab")
		)
		(fp_line
			(start 0.12065 -0.3048)
			(end 0.67945 -0.3048)
			(stroke
				(width 0.1)
				(type default)
			)
			(layer "F.Fab")
		)
		(fp_line
			(start 0.120396 0.3048)
			(end 0.120396 0.2794)
			(stroke
				(width 0.1)
				(type default)
			)
			(layer "F.Fab")
		)
		(fp_line
			(start 0.120396 0.2794)
			(end -0.12065 0.2794)
			(stroke
				(width 0.1)
				(type default)
			)
			(layer "F.Fab")
		)
		(fp_line
			(start -0.12065 0.3048)
			(end -0.67945 0.3048)
			(stroke
				(width 0.1)
				(type default)
			)
			(layer "F.Fab")
		)
		(fp_line
			(start -0.12065 0.2794)
			(end -0.12065 0.3048)
			(stroke
				(width 0.1)
				(type default)
			)
			(layer "F.Fab")
		)
		(fp_line
			(start -0.12065 -0.2794)
			(end 0.12065 -0.2794)
			(stroke
				(width 0.1)
				(type default)
			)
			(layer "F.Fab")
		)
		(fp_line
			(start -0.12065 -0.305054)
			(end -0.12065 -0.2794)
			(stroke
				(width 0.1)
				(type default)
			)
			(layer "F.Fab")
		)
		(fp_line
			(start -0.67945 0.3048)
			(end -0.67945 -0.305054)
			(stroke
				(width 0.1)
				(type default)
			)
			(layer "F.Fab")
		)
		(fp_line
			(start -0.67945 -0.305054)
			(end -0.12065 -0.305054)
			(stroke
				(width 0.1)
				(type default)
			)
			(layer "F.Fab")
		)
		(pad "1" smd circle
			(at -0.40005 0 180)
			(size 0 0)
			(layers "F.Cu" "F.Mask" "F.Paste")
			(net "SW_P5V_AUX_BST")
		)
		(pad "2" smd circle
			(at 0.40005 0 180)
			(size 0 0)
			(layers "F.Cu" "F.Mask" "F.Paste")
			(net "SW_P5V_AUX_SW")
		)
	)
	(footprint ""
		(layer "F.Cu")
		(at 76.839318 -17.777968 -90)
		(property "Reference" "PR3806"
			(at 0 0 270)
			(layer "F.SilkS")
			(hide yes)
			(effects
				(font
					(size 1.27 1.27)
				)
			)
		)
		(property "Value" ""
			(at 0 0 270)
			(layer "F.Fab")
			(effects
				(font
					(size 1.27 1.27)
				)
			)
		)
		(duplicate_pad_numbers_are_jumpers no)
		(fp_line
			(start -0.7874 0.4064)
			(end -0.7874 -0.4064)
			(stroke
				(width 0.1524)
				(type default)
			)
			(layer "F.SilkS")
		)
		(fp_line
			(start 0.7874 0.4064)
			(end -0.7874 0.4064)
			(stroke
				(width 0.1524)
				(type default)
			)
			(layer "F.SilkS")
		)
		(fp_line
			(start -0.7874 -0.4064)
			(end 0.7874 -0.4064)
			(stroke
				(width 0.1524)
				(type default)
			)
			(layer "F.SilkS")
		)
		(fp_line
			(start 0.7874 -0.4064)
			(end 0.7874 0.4064)
			(stroke
				(width 0.1524)
				(type default)
			)
			(layer "F.SilkS")
		)
		(fp_line
			(start -0.67945 0.3048)
			(end -0.67945 -0.305054)
			(stroke
				(width 0.1)
				(type default)
			)
			(layer "F.Fab")
		)
		(fp_line
			(start -0.12065 0.3048)
			(end -0.67945 0.3048)
			(stroke
				(width 0.1)
				(type default)
			)
			(layer "F.Fab")
		)
		(fp_line
			(start 0.120396 0.3048)
			(end 0.120396 0.2794)
			(stroke
				(width 0.1)
				(type default)
			)
			(layer "F.Fab")
		)
		(fp_line
			(start 0.67945 0.3048)
			(end 0.120396 0.3048)
			(stroke
				(width 0.1)
				(type default)
			)
			(layer "F.Fab")
		)
		(fp_line
			(start -0.12065 0.2794)
			(end -0.12065 0.3048)
			(stroke
				(width 0.1)
				(type default)
			)
			(layer "F.Fab")
		)
		(fp_line
			(start 0.120396 0.2794)
			(end -0.12065 0.2794)
			(stroke
				(width 0.1)
				(type default)
			)
			(layer "F.Fab")
		)
		(fp_line
			(start -0.12065 -0.2794)
			(end 0.12065 -0.2794)
			(stroke
				(width 0.1)
				(type default)
			)
			(layer "F.Fab")
		)
		(fp_line
			(start 0.12065 -0.2794)
			(end 0.12065 -0.3048)
			(stroke
				(width 0.1)
				(type default)
			)
			(layer "F.Fab")
		)
		(fp_line
			(start 0.12065 -0.3048)
			(end 0.67945 -0.3048)
			(stroke
				(width 0.1)
				(type default)
			)
			(layer "F.Fab")
		)
		(fp_line
			(start 0.67945 -0.3048)
			(end 0.67945 0.3048)
			(stroke
				(width 0.1)
				(type default)
			)
			(layer "F.Fab")
		)
		(fp_line
			(start -0.67945 -0.305054)
			(end -0.12065 -0.305054)
			(stroke
				(width 0.1)
				(type default)
			)
			(layer "F.Fab")
		)
		(fp_line
			(start -0.12065 -0.305054)
			(end -0.12065 -0.2794)
			(stroke
				(width 0.1)
				(type default)
			)
			(layer "F.Fab")
		)
		(pad "1" smd circle
			(at -0.40005 0 270)
			(size 0 0)
			(layers "F.Cu" "F.Mask" "F.Paste")
			(net "P12V_OCP_UV_2")
		)
		(pad "2" smd circle
			(at 0.40005 0 270)
			(size 0 0)
			(layers "F.Cu" "F.Mask" "F.Paste")
			(net "P12V_OCP_OV_2")
		)
	)
	(footprint ""
		(layer "F.Cu")
		(at 422.022524 -149.239224 -90)
		(property "Reference" "PC177"
			(at 0 0 270)
			(layer "F.SilkS")
			(hide yes)
			(effects
				(font
					(size 1.27 1.27)
				)
			)
		)
		(property "Value" ""
			(at 0 0 270)
			(layer "F.Fab")
			(effects
				(font
					(size 1.27 1.27)
				)
			)
		)
		(duplicate_pad_numbers_are_jumpers no)
		(fp_line
			(start -0.7874 0.4064)
			(end -0.7874 -0.4064)
			(stroke
				(width 0.1524)
				(type default)
			)
			(layer "F.SilkS")
		)
		(fp_line
			(start 0.7874 0.4064)
			(end -0.7874 0.4064)
			(stroke
				(width 0.1524)
				(type default)
			)
			(layer "F.SilkS")
		)
		(fp_line
			(start -0.7874 -0.4064)
			(end 0.7874 -0.4064)
			(stroke
				(width 0.1524)
				(type default)
			)
			(layer "F.SilkS")
		)
		(fp_line
			(start 0.7874 -0.4064)
			(end 0.7874 0.4064)
			(stroke
				(width 0.1524)
				(type default)
			)
			(layer "F.SilkS")
		)
		(fp_line
			(start -0.67945 0.3048)
			(end -0.67945 -0.305054)
			(stroke
				(width 0.1)
				(type default)
			)
			(layer "F.Fab")
		)
		(fp_line
			(start -0.12065 0.3048)
			(end -0.67945 0.3048)
			(stroke
				(width 0.1)
				(type default)
			)
			(layer "F.Fab")
		)
		(fp_line
			(start 0.120396 0.3048)
			(end 0.120396 0.2794)
			(stroke
				(width 0.1)
				(type default)
			)
			(layer "F.Fab")
		)
		(fp_line
			(start 0.67945 0.3048)
			(end 0.120396 0.3048)
			(stroke
				(width 0.1)
				(type default)
			)
			(layer "F.Fab")
		)
		(fp_line
			(start -0.12065 0.2794)
			(end -0.12065 0.3048)
			(stroke
				(width 0.1)
				(type default)
			)
			(layer "F.Fab")
		)
		(fp_line
			(start 0.120396 0.2794)
			(end -0.12065 0.2794)
			(stroke
				(width 0.1)
				(type default)
			)
			(layer "F.Fab")
		)
		(fp_line
			(start -0.12065 -0.2794)
			(end 0.12065 -0.2794)
			(stroke
				(width 0.1)
				(type default)
			)
			(layer "F.Fab")
		)
		(fp_line
			(start 0.12065 -0.2794)
			(end 0.12065 -0.3048)
			(stroke
				(width 0.1)
				(type default)
			)
			(layer "F.Fab")
		)
		(fp_line
			(start 0.12065 -0.3048)
			(end 0.67945 -0.3048)
			(stroke
				(width 0.1)
				(type default)
			)
			(layer "F.Fab")
		)
		(fp_line
			(start 0.67945 -0.3048)
			(end 0.67945 0.3048)
			(stroke
				(width 0.1)
				(type default)
			)
			(layer "F.Fab")
		)
		(fp_line
			(start -0.67945 -0.305054)
			(end -0.12065 -0.305054)
			(stroke
				(width 0.1)
				(type default)
			)
			(layer "F.Fab")
		)
		(fp_line
			(start -0.12065 -0.305054)
			(end -0.12065 -0.2794)
			(stroke
				(width 0.1)
				(type default)
			)
			(layer "F.Fab")
		)
		(pad "1" smd circle
			(at -0.40005 0 270)
			(size 0 0)
			(layers "F.Cu" "F.Mask" "F.Paste")
			(net "SW_P12V_PVCCINFAON_CPU0_FLT")
		)
		(pad "2" smd circle
			(at 0.40005 0 270)
			(size 0 0)
			(layers "F.Cu" "F.Mask" "F.Paste")
			(net "GND")
		)
	)
	(footprint ""
		(layer "F.Cu")
		(at 65.828926 -20.04822 180)
		(property "Reference" "PC2143"
			(at 0 0 180)
			(layer "F.SilkS")
			(hide yes)
			(effects
				(font
					(size 1.27 1.27)
				)
			)
		)
		(property "Value" ""
			(at 0 0 180)
			(layer "F.Fab")
			(effects
				(font
					(size 1.27 1.27)
				)
			)
		)
		(duplicate_pad_numbers_are_jumpers no)
		(fp_line
			(start 1.524 0.762)
			(end -1.524 0.762)
			(stroke
				(width 0.1524)
				(type default)
			)
			(layer "F.SilkS")
		)
		(fp_line
			(start 1.524 -0.762)
			(end 1.524 0.762)
			(stroke
				(width 0.1524)
				(type default)
			)
			(layer "F.SilkS")
		)
		(fp_line
			(start -1.524 0.762)
			(end -1.524 -0.762)
			(stroke
				(width 0.1524)
				(type default)
			)
			(layer "F.SilkS")
		)
		(fp_line
			(start -1.524 -0.762)
			(end 1.524 -0.762)
			(stroke
				(width 0.1524)
				(type default)
			)
			(layer "F.SilkS")
		)
		(fp_line
			(start 1.1049 0.724916)
			(end 1.1049 -0.724916)
			(stroke
				(width 0.1)
				(type default)
			)
			(layer "F.Fab")
		)
		(fp_line
			(start 1.1049 -0.724916)
			(end -1.1049 -0.724916)
			(stroke
				(width 0.1)
				(type default)
			)
			(layer "F.Fab")
		)
		(fp_line
			(start -1.1049 0.724916)
			(end 1.1049 0.724916)
			(stroke
				(width 0.1)
				(type default)
			)
			(layer "F.Fab")
		)
		(fp_line
			(start -1.1049 -0.724916)
			(end -1.1049 0.724916)
			(stroke
				(width 0.1)
				(type default)
			)
			(layer "F.Fab")
		)
		(pad "1" smd rect
			(at -0.889 0)
			(size 1.016 1.27)
			(layers "F.Cu" "F.Mask" "F.Paste")
			(net "P12V_OCP_V3_2")
		)
		(pad "2" smd rect
			(at 0.889 0)
			(size 1.016 1.27)
			(layers "F.Cu" "F.Mask" "F.Paste")
			(net "GND")
		)
	)
	(footprint ""
		(layer "F.Cu")
		(at 336.750914 -327.768204)
		(property "Reference" "PL9"
			(at -6.423914 4.195826 0)
			(unlocked yes)
			(layer "F.SilkS")
			(effects
				(font
					(size 0.7874 0.5842)
					(thickness 0.1524)
				)
				(justify left)
			)
		)
		(property "Value" ""
			(at 0 0 0)
			(layer "F.Fab")
			(effects
				(font
					(size 1.27 1.27)
				)
			)
		)
		(duplicate_pad_numbers_are_jumpers no)
		(fp_line
			(start -3.750056 -5.500116)
			(end -2.393442 -5.500116)
			(stroke
				(width 0.1524)
				(type default)
			)
			(layer "F.SilkS")
		)
		(fp_line
			(start -3.750056 5.500116)
			(end -3.750056 -5.500116)
			(stroke
				(width 0.1524)
				(type default)
			)
			(layer "F.SilkS")
		)
		(fp_line
			(start -2.393442 5.500116)
			(end -3.750056 5.500116)
			(stroke
				(width 0.1524)
				(type default)
			)
			(layer "F.SilkS")
		)
		(fp_line
			(start 2.393442 5.500116)
			(end 3.750056 5.500116)
			(stroke
				(width 0.1524)
				(type default)
			)
			(layer "F.SilkS")
		)
		(fp_line
			(start 3.750056 -5.500116)
			(end 2.393442 -5.500116)
			(stroke
				(width 0.1524)
				(type default)
			)
			(layer "F.SilkS")
		)
		(fp_line
			(start 3.750056 -1.507744)
			(end 3.750056 -5.500116)
			(stroke
				(width 0.1524)
				(type default)
			)
			(layer "F.SilkS")
		)
		(fp_line
			(start 3.750056 5.500116)
			(end 3.750056 -0.364744)
			(stroke
				(width 0.1524)
				(type default)
			)
			(layer "F.SilkS")
		)
		(fp_poly
			(pts
				(xy -3.125978 -6.963664) (xy -2.766822 -5.885942) (xy -3.844544 -6.245352)
			)
			(stroke
				(width 0)
				(type default)
			)
			(fill yes)
			(layer "F.SilkS")
		)
		(fp_line
			(start -3.750056 -5.500116)
			(end -3.750056 5.500116)
			(stroke
				(width 0.1)
				(type default)
			)
			(layer "F.Fab")
		)
		(fp_line
			(start -3.750056 5.500116)
			(end 3.750056 5.500116)
			(stroke
				(width 0.1)
				(type default)
			)
			(layer "F.Fab")
		)
		(fp_line
			(start 3.750056 -5.500116)
			(end -3.750056 -5.500116)
			(stroke
				(width 0.1)
				(type default)
			)
			(layer "F.Fab")
		)
		(fp_line
			(start 3.750056 5.500116)
			(end 3.750056 -5.500116)
			(stroke
				(width 0.1)
				(type default)
			)
			(layer "F.Fab")
		)
		(fp_poly
			(pts
				(xy -4.9276 -4.757928) (xy -4.9276 -3.741928) (xy -3.9116 -4.249928)
			)
			(stroke
				(width 0)
				(type default)
			)
			(fill yes)
			(layer "F.Fab")
		)
		(pad "1" smd rect
			(at 0 -4.249928 270)
			(size 2.413 4.5212)
			(layers "F.Cu" "F.Mask" "F.Paste")
			(net "SW_PVCCIN_CPU0_SW6")
		)
		(pad "2" smd rect
			(at 0 -1.175004 270)
			(size 1.3716 4.5212)
			(layers "F.Cu" "F.Mask" "F.Paste")
			(net "IND_P0_CPL6")
		)
		(pad "3" smd rect
			(at 0 1.175004 270)
			(size 1.3716 4.5212)
			(layers "F.Cu" "F.Mask" "F.Paste")
			(net "IND_P0_CPL1")
		)
		(pad "4" smd rect
			(at 0 4.249928 270)
			(size 2.413 4.5212)
			(layers "F.Cu" "F.Mask" "F.Paste")
			(net "PVCCIN_CPU0")
		)
	)
)
